(kicad_pcb
	(version 20260206)
	(generator "pcbnew")
	(generator_version "10.0")
	(general
		(thickness 1.6)
		(legacy_teardrops no)
	)
	(paper "A4")
	(title_block
		(title "v1-pdb — T6M_PDB_D_0927_0900.brd")
		(comment 1 "Open CloudServer (Microsoft) / footprints 258-266 of 321")
	)
	(layers
		(0 "F.Cu" signal "TOP")
		(4 "In1.Cu" signal "GND")
		(6 "In2.Cu" signal "IN1")
		(8 "In3.Cu" signal "VCC")
		(10 "In4.Cu" signal "VCC1")
		(12 "In5.Cu" signal "IN2")
		(14 "In6.Cu" signal "GND1")
		(2 "B.Cu" signal "BOTTOM")
		(9 "F.Adhes" user "F.Adhesive")
		(11 "B.Adhes" user "B.Adhesive")
		(13 "F.Paste" user "Package Geometry/Pastemask Top")
		(15 "B.Paste" user "Package Geometry/Pastemask Bottom")
		(5 "F.SilkS" user "Ref Des/Silkscreen Top")
		(7 "B.SilkS" user "Ref Des/Silkscreen Bottom")
		(1 "F.Mask" user "Board Geometry/Soldermask Top")
		(3 "B.Mask" user "Board Geometry/Soldermask Bottom")
		(17 "Dwgs.User" user "User.Drawings")
		(19 "Cmts.User" user "User.Comments")
		(21 "Eco1.User" user "User.Eco1")
		(23 "Eco2.User" user "User.Eco2")
		(25 "Edge.Cuts" user "Board Geometry/Outline")
		(27 "Margin" user)
		(31 "F.CrtYd" user "Package Geometry/Place Bound Top")
		(29 "B.CrtYd" user "Package Geometry/Place Bound Bottom")
		(35 "F.Fab" user "Ref Des/Assembly Top")
		(33 "B.Fab" user "Ref Des/Assembly Bottom")
	)
	(footprint ""
		(layer "F.Cu")
		(at 80.932782 -295.215564 180)
		(property "Reference" "R124"
			(at 1.303528 -1.245108 0)
			(unlocked yes)
			(layer "F.SilkS")
			(effects
				(font
					(size 0.7874 0.5842)
					(thickness 0.1524)
				)
				(justify left)
			)
		)
		(property "Value" ""
			(at 0 0 180)
			(layer "F.Fab")
			(effects
				(font
					(size 1.27 1.27)
				)
			)
		)
		(duplicate_pad_numbers_are_jumpers no)
		(fp_line
			(start 0.7874 0.4064)
			(end -0.7874 0.4064)
			(stroke
				(width 0.1524)
				(type default)
			)
			(layer "F.SilkS")
		)
		(fp_line
			(start 0.7874 -0.4064)
			(end 0.7874 0.4064)
			(stroke
				(width 0.1524)
				(type default)
			)
			(layer "F.SilkS")
		)
		(fp_line
			(start -0.7874 0.4064)
			(end -0.7874 -0.4064)
			(stroke
				(width 0.1524)
				(type default)
			)
			(layer "F.SilkS")
		)
		(fp_line
			(start -0.7874 -0.4064)
			(end 0.7874 -0.4064)
			(stroke
				(width 0.1524)
				(type default)
			)
			(layer "F.SilkS")
		)
		(fp_poly
			(pts
				(xy -0.508 0.2794) (xy -0.508 0.2286) (xy -0.635 0.2286) (xy -0.635 -0.254) (xy -0.5334 -0.254)
				(xy -0.5334 -0.2794) (xy 0.5334 -0.2794) (xy 0.5334 -0.254) (xy 0.635 -0.254) (xy 0.635 0.254) (xy 0.5334 0.254)
				(xy 0.5334 0.2794)
			)
			(stroke
				(width 0)
				(type default)
			)
			(fill no)
			(layer "F.CrtYd")
		)
		(pad "1" smd rect
			(at 0.40005 0 180)
			(size 0.4572 0.508)
			(layers "F.Cu" "F.Mask" "F.Paste")
			(net "PSU4_REMOTE_R2_N")
		)
		(pad "2" smd rect
			(at -0.40005 0 180)
			(size 0.4572 0.508)
			(layers "F.Cu" "F.Mask" "F.Paste")
			(net "GND")
		)
	)
	(footprint ""
		(layer "F.Cu")
		(at 25.931622 -95.65132)
		(property "Reference" "R47"
			(at -4.080256 -0.075692 0)
			(unlocked yes)
			(layer "F.SilkS")
			(effects
				(font
					(size 0.7874 0.5842)
					(thickness 0.1524)
				)
				(justify left)
			)
		)
		(property "Value" ""
			(at 0 0 0)
			(layer "F.Fab")
			(effects
				(font
					(size 1.27 1.27)
				)
			)
		)
		(duplicate_pad_numbers_are_jumpers no)
		(fp_line
			(start -0.7874 -0.4064)
			(end 0.7874 -0.4064)
			(stroke
				(width 0.1524)
				(type default)
			)
			(layer "F.SilkS")
		)
		(fp_line
			(start -0.7874 0.4064)
			(end -0.7874 -0.4064)
			(stroke
				(width 0.1524)
				(type default)
			)
			(layer "F.SilkS")
		)
		(fp_line
			(start 0.7874 -0.4064)
			(end 0.7874 0.4064)
			(stroke
				(width 0.1524)
				(type default)
			)
			(layer "F.SilkS")
		)
		(fp_line
			(start 0.7874 0.4064)
			(end -0.7874 0.4064)
			(stroke
				(width 0.1524)
				(type default)
			)
			(layer "F.SilkS")
		)
		(fp_poly
			(pts
				(xy -0.508 0.2794) (xy -0.508 0.2286) (xy -0.635 0.2286) (xy -0.635 -0.254) (xy -0.5334 -0.254)
				(xy -0.5334 -0.2794) (xy 0.5334 -0.2794) (xy 0.5334 -0.254) (xy 0.635 -0.254) (xy 0.635 0.254) (xy 0.5334 0.254)
				(xy 0.5334 0.2794)
			)
			(stroke
				(width 0)
				(type default)
			)
			(fill no)
			(layer "F.CrtYd")
		)
		(pad "1" smd rect
			(at 0.40005 0)
			(size 0.4572 0.508)
			(layers "F.Cu" "F.Mask" "F.Paste")
			(net "PSU2_RESET")
		)
		(pad "2" smd rect
			(at -0.40005 0)
			(size 0.4572 0.508)
			(layers "F.Cu" "F.Mask" "F.Paste")
			(net "GND")
		)
	)
	(footprint ""
		(layer "F.Cu")
		(at 71.815198 -193.582544 -90)
		(property "Reference" "C31"
			(at 0.978662 -4.304284 90)
			(unlocked yes)
			(layer "F.SilkS")
			(effects
				(font
					(size 0.7874 0.5842)
					(thickness 0.1524)
				)
				(justify left)
			)
		)
		(property "Value" ""
			(at 0 0 270)
			(layer "F.Fab")
			(effects
				(font
					(size 1.27 1.27)
				)
			)
		)
		(duplicate_pad_numbers_are_jumpers no)
		(fp_line
			(start -0.7874 0.4064)
			(end -0.7874 -0.4064)
			(stroke
				(width 0.1524)
				(type default)
			)
			(layer "F.SilkS")
		)
		(fp_line
			(start 0.7874 0.4064)
			(end -0.7874 0.4064)
			(stroke
				(width 0.1524)
				(type default)
			)
			(layer "F.SilkS")
		)
		(fp_line
			(start 0 0.381)
			(end 0 -0.381)
			(stroke
				(width 0.1524)
				(type default)
			)
			(layer "F.SilkS")
		)
		(fp_line
			(start -0.7874 -0.4064)
			(end 0.7874 -0.4064)
			(stroke
				(width 0.1524)
				(type default)
			)
			(layer "F.SilkS")
		)
		(fp_line
			(start 0.7874 -0.4064)
			(end 0.7874 0.4064)
			(stroke
				(width 0.1524)
				(type default)
			)
			(layer "F.SilkS")
		)
		(fp_poly
			(pts
				(xy -0.5334 0.254) (xy -0.635 0.254) (xy -0.635 0.2286) (xy -0.635 -0.254) (xy -0.5334 -0.254) (xy -0.5334 -0.2794)
				(xy 0.5334 -0.2794) (xy 0.5334 -0.254) (xy 0.635 -0.254) (xy 0.635 0.254) (xy 0.5334 0.254) (xy 0.5334 0.2794)
				(xy -0.508 0.2794) (xy -0.5334 0.2794)
			)
			(stroke
				(width 0)
				(type default)
			)
			(fill no)
			(layer "F.CrtYd")
		)
		(pad "1" smd rect
			(at 0.40005 0 270)
			(size 0.4572 0.508)
			(layers "F.Cu" "F.Mask" "F.Paste")
			(net "P12V")
		)
		(pad "2" smd rect
			(at -0.40005 0 270)
			(size 0.4572 0.508)
			(layers "F.Cu" "F.Mask" "F.Paste")
			(net "GND")
		)
	)
	(footprint ""
		(layer "F.Cu")
		(at 91.399868 -153.359866)
		(property "Reference" "H22"
			(at -5.1308 -5.23113 0)
			(unlocked yes)
			(layer "F.SilkS")
			(effects
				(font
					(size 0.7874 0.5842)
					(thickness 0.1524)
				)
				(justify left)
			)
		)
		(property "Value" ""
			(at 0 0 0)
			(layer "F.Fab")
			(effects
				(font
					(size 1.27 1.27)
				)
			)
		)
		(duplicate_pad_numbers_are_jumpers no)
		(fp_circle
			(center 0 0)
			(end 4.826 0)
			(stroke
				(width 0.1524)
				(type default)
			)
			(fill no)
			(layer "F.SilkS")
		)
		(fp_circle
			(center 0 0)
			(end 4.826 0)
			(stroke
				(width 0.1524)
				(type default)
			)
			(fill no)
			(layer "B.SilkS")
		)
		(fp_poly
			(pts
				(arc
					(start 0 4.0132)
					(mid 0 -4.0132)
					(end 0 4.0132)
				)
			)
			(stroke
				(width 0)
				(type default)
			)
			(fill no)
			(layer "F.CrtYd")
		)
		(pad "" np_thru_hole circle
			(at 0 0)
			(size 8.001 8.001)
			(drill 8.001)
			(layers "*.Cu" "*.Mask")
			(clearance 0.381)
			(thermal_gap 0.381)
		)
		(zone
			(layers "F.Cu" "B.Cu" "In1.Cu" "In2.Cu" "In3.Cu" "In4.Cu" "In5.Cu" "In6.Cu")
			(hatch none 0.5)
			(connect_pads
				(clearance 0)
			)
			(min_thickness 0.25)
			(keepout
				(tracks not_allowed)
				(vias allowed)
				(pads allowed)
				(copperpour not_allowed)
				(footprints allowed)
			)
			(placement
				(enabled no)
				(sheetname "")
			)
			(fill
				(thermal_gap 0.5)
				(thermal_bridge_width 0.5)
				(island_removal_mode 0)
			)
			(polygon
				(pts
					(arc
						(start 91.399868 -148.838666)
						(mid 91.399868 -157.881066)
						(end 91.399868 -148.838666)
					)
				)
			)
		)
	)
	(footprint ""
		(layer "F.Cu")
		(at 72.520302 -87.145368 90)
		(property "Reference" "C20"
			(at -4.402836 -0.015748 90)
			(unlocked yes)
			(layer "F.SilkS")
			(effects
				(font
					(size 0.7874 0.5842)
					(thickness 0.1524)
				)
				(justify left)
			)
		)
		(property "Value" ""
			(at 0 0 90)
			(layer "F.Fab")
			(effects
				(font
					(size 1.27 1.27)
				)
			)
		)
		(duplicate_pad_numbers_are_jumpers no)
		(fp_line
			(start 0.7874 -0.4064)
			(end 0.7874 0.4064)
			(stroke
				(width 0.1524)
				(type default)
			)
			(layer "F.SilkS")
		)
		(fp_line
			(start -0.7874 -0.4064)
			(end 0.7874 -0.4064)
			(stroke
				(width 0.1524)
				(type default)
			)
			(layer "F.SilkS")
		)
		(fp_line
			(start 0 0.381)
			(end 0 -0.381)
			(stroke
				(width 0.1524)
				(type default)
			)
			(layer "F.SilkS")
		)
		(fp_line
			(start 0.7874 0.4064)
			(end -0.7874 0.4064)
			(stroke
				(width 0.1524)
				(type default)
			)
			(layer "F.SilkS")
		)
		(fp_line
			(start -0.7874 0.4064)
			(end -0.7874 -0.4064)
			(stroke
				(width 0.1524)
				(type default)
			)
			(layer "F.SilkS")
		)
		(fp_poly
			(pts
				(xy -0.5334 0.254) (xy -0.635 0.254) (xy -0.635 0.2286) (xy -0.635 -0.254) (xy -0.5334 -0.254) (xy -0.5334 -0.2794)
				(xy 0.5334 -0.2794) (xy 0.5334 -0.254) (xy 0.635 -0.254) (xy 0.635 0.254) (xy 0.5334 0.254) (xy 0.5334 0.2794)
				(xy -0.508 0.2794) (xy -0.5334 0.2794)
			)
			(stroke
				(width 0)
				(type default)
			)
			(fill no)
			(layer "F.CrtYd")
		)
		(pad "1" smd rect
			(at 0.40005 0 90)
			(size 0.4572 0.508)
			(layers "F.Cu" "F.Mask" "F.Paste")
			(net "P12V")
		)
		(pad "2" smd rect
			(at -0.40005 0 90)
			(size 0.4572 0.508)
			(layers "F.Cu" "F.Mask" "F.Paste")
			(net "GND")
		)
	)
	(footprint ""
		(layer "F.Cu")
		(at 50.54981 -507.67742 180)
		(property "Reference" "CE23"
			(at 2.73939 5.49021 0)
			(unlocked yes)
			(layer "F.SilkS")
			(effects
				(font
					(size 0.7874 0.5842)
					(thickness 0.1524)
				)
				(justify left)
			)
		)
		(property "Value" ""
			(at 0 0 180)
			(layer "F.Fab")
			(effects
				(font
					(size 1.27 1.27)
				)
			)
		)
		(duplicate_pad_numbers_are_jumpers no)
		(fp_line
			(start 0 -4.2672)
			(end 0 4.2672)
			(stroke
				(width 0.1524)
				(type default)
			)
			(layer "F.SilkS")
		)
		(fp_circle
			(center 0 0)
			(end -4.2672 0)
			(stroke
				(width 0.1524)
				(type default)
			)
			(fill no)
			(layer "F.SilkS")
		)
		(fp_poly
			(pts
				(arc
					(start 0 -4.2672)
					(mid 4.2672 0)
					(end 0 4.2672)
				)
			)
			(stroke
				(width 0)
				(type default)
			)
			(fill yes)
			(layer "F.SilkS")
		)
		(fp_poly
			(pts
				(xy -2.5146 -0.762) (xy -0.9906 -0.762) (xy -0.9906 0.762) (xy -2.5146 0.762)
			)
			(stroke
				(width 0)
				(type default)
			)
			(fill no)
			(layer "B.CrtYd")
		)
		(fp_poly
			(pts
				(arc
					(start 1.7526 0.762)
					(mid 2.291415 -0.538815)
					(end 0.9906 0)
				)
				(arc
					(start 0.9906 0.0254)
					(mid 1.206345 0.546255)
					(end 1.7272 0.762)
				)
			)
			(stroke
				(width 0)
				(type default)
			)
			(fill no)
			(layer "B.CrtYd")
		)
		(fp_poly
			(pts
				(arc
					(start -4.2672 0)
					(mid 4.2672 0)
					(end -4.2672 0)
				)
			)
			(stroke
				(width 0)
				(type default)
			)
			(fill no)
			(layer "F.CrtYd")
		)
		(fp_circle
			(center 0 0)
			(end -4.2672 0)
			(stroke
				(width 0.1)
				(type default)
			)
			(fill no)
			(layer "F.Fab")
		)
		(fp_text user "+"
			(at -5.619496 0.15367 180)
			(unlocked yes)
			(layer "F.SilkS")
			(effects
				(font
					(size 0.7874 0.5842)
					(thickness 0.1524)
				)
				(justify left)
			)
		)
		(fp_text user "+"
			(at -5.6642 -0.34925 180)
			(unlocked yes)
			(layer "F.Fab")
			(effects
				(font
					(size 1.905 1.4224)
					(thickness 0.000001)
				)
				(justify left)
			)
		)
		(pad "1" thru_hole rect
			(at -1.75006 0 180)
			(size 1.397 1.397)
			(drill 0.9144)
			(layers "*.Cu" "*.Mask")
			(remove_unused_layers no)
			(net "P12V")
			(clearance 0.0127)
			(thermal_gap 0.0127)
			(padstack
				(mode front_inner_back)
				(layer "Inner"
					(shape circle)
					(size 1.397 1.397)
					(clearance 0.0127)
				)
				(layer "B.Cu"
					(shape rect)
					(size 1.397 1.397)
					(clearance 0.0127)
				)
			)
		)
		(pad "2" thru_hole circle
			(at 1.75006 0 180)
			(size 1.397 1.397)
			(drill 0.9144)
			(layers "*.Cu" "*.Mask")
			(remove_unused_layers no)
			(net "GND")
			(clearance 0.0127)
			(thermal_gap 0.0127)
		)
	)
	(footprint ""
		(layer "F.Cu")
		(at 50.39868 -463.099658 180)
		(property "Reference" "CE22"
			(at -4.925568 2.154174 0)
			(unlocked yes)
			(layer "F.SilkS")
			(effects
				(font
					(size 0.7874 0.5842)
					(thickness 0.1524)
				)
				(justify left)
			)
		)
		(property "Value" ""
			(at 0 0 180)
			(layer "F.Fab")
			(effects
				(font
					(size 1.27 1.27)
				)
			)
		)
		(duplicate_pad_numbers_are_jumpers no)
		(fp_line
			(start 0 -4.2672)
			(end 0 4.2672)
			(stroke
				(width 0.1524)
				(type default)
			)
			(layer "F.SilkS")
		)
		(fp_circle
			(center 0 0)
			(end -4.2672 0)
			(stroke
				(width 0.1524)
				(type default)
			)
			(fill no)
			(layer "F.SilkS")
		)
		(fp_poly
			(pts
				(arc
					(start 0 -4.2672)
					(mid 4.2672 0)
					(end 0 4.2672)
				)
			)
			(stroke
				(width 0)
				(type default)
			)
			(fill yes)
			(layer "F.SilkS")
		)
		(fp_poly
			(pts
				(xy -2.5146 -0.762) (xy -0.9906 -0.762) (xy -0.9906 0.762) (xy -2.5146 0.762)
			)
			(stroke
				(width 0)
				(type default)
			)
			(fill no)
			(layer "B.CrtYd")
		)
		(fp_poly
			(pts
				(arc
					(start 1.7526 0.762)
					(mid 2.291415 -0.538815)
					(end 0.9906 0)
				)
				(arc
					(start 0.9906 0.0254)
					(mid 1.206345 0.546255)
					(end 1.7272 0.762)
				)
			)
			(stroke
				(width 0)
				(type default)
			)
			(fill no)
			(layer "B.CrtYd")
		)
		(fp_poly
			(pts
				(arc
					(start -4.2672 0)
					(mid 4.2672 0)
					(end -4.2672 0)
				)
			)
			(stroke
				(width 0)
				(type default)
			)
			(fill no)
			(layer "F.CrtYd")
		)
		(fp_circle
			(center 0 0)
			(end -4.2672 0)
			(stroke
				(width 0.1)
				(type default)
			)
			(fill no)
			(layer "F.Fab")
		)
		(fp_text user "+"
			(at -5.6642 0.15367 180)
			(unlocked yes)
			(layer "F.SilkS")
			(effects
				(font
					(size 0.7874 0.5842)
					(thickness 0.1524)
				)
				(justify left)
			)
		)
		(fp_text user "+"
			(at -5.6642 -0.34925 180)
			(unlocked yes)
			(layer "F.Fab")
			(effects
				(font
					(size 1.905 1.4224)
					(thickness 0.000001)
				)
				(justify left)
			)
		)
		(pad "1" thru_hole rect
			(at -1.75006 0 180)
			(size 1.397 1.397)
			(drill 0.9144)
			(layers "*.Cu" "*.Mask")
			(remove_unused_layers no)
			(net "P12V")
			(clearance 0.0127)
			(thermal_gap 0.0127)
			(padstack
				(mode front_inner_back)
				(layer "Inner"
					(shape circle)
					(size 1.397 1.397)
					(clearance 0.0127)
				)
				(layer "B.Cu"
					(shape rect)
					(size 1.397 1.397)
					(clearance 0.0127)
				)
			)
		)
		(pad "2" thru_hole circle
			(at 1.75006 0 180)
			(size 1.397 1.397)
			(drill 0.9144)
			(layers "*.Cu" "*.Mask")
			(remove_unused_layers no)
			(net "GND")
			(clearance 0.0127)
			(thermal_gap 0.0127)
		)
	)
	(footprint ""
		(layer "F.Cu")
		(at 13.463778 -325.064882 180)
		(property "Reference" "R142"
			(at -1.084834 -0.000254 0)
			(unlocked yes)
			(layer "F.SilkS")
			(effects
				(font
					(size 0.7874 0.5842)
					(thickness 0.1524)
				)
				(justify left)
			)
		)
		(property "Value" ""
			(at 0 0 180)
			(layer "F.Fab")
			(effects
				(font
					(size 1.27 1.27)
				)
			)
		)
		(duplicate_pad_numbers_are_jumpers no)
		(fp_line
			(start 0.7874 0.4064)
			(end -0.7874 0.4064)
			(stroke
				(width 0.1524)
				(type default)
			)
			(layer "F.SilkS")
		)
		(fp_line
			(start 0.7874 -0.4064)
			(end 0.7874 0.4064)
			(stroke
				(width 0.1524)
				(type default)
			)
			(layer "F.SilkS")
		)
		(fp_line
			(start -0.7874 0.4064)
			(end -0.7874 -0.4064)
			(stroke
				(width 0.1524)
				(type default)
			)
			(layer "F.SilkS")
		)
		(fp_line
			(start -0.7874 -0.4064)
			(end 0.7874 -0.4064)
			(stroke
				(width 0.1524)
				(type default)
			)
			(layer "F.SilkS")
		)
		(fp_poly
			(pts
				(xy -0.508 0.2794) (xy -0.508 0.2286) (xy -0.635 0.2286) (xy -0.635 -0.254) (xy -0.5334 -0.254)
				(xy -0.5334 -0.2794) (xy 0.5334 -0.2794) (xy 0.5334 -0.254) (xy 0.635 -0.254) (xy 0.635 0.254) (xy 0.5334 0.254)
				(xy 0.5334 0.2794)
			)
			(stroke
				(width 0)
				(type default)
			)
			(fill no)
			(layer "F.CrtYd")
		)
		(pad "1" smd rect
			(at 0.40005 0 180)
			(size 0.4572 0.508)
			(layers "F.Cu" "F.Mask" "F.Paste")
			(net "FAN1_TACH")
		)
		(pad "2" smd rect
			(at -0.40005 0 180)
			(size 0.4572 0.508)
			(layers "F.Cu" "F.Mask" "F.Paste")
			(net "P12V")
		)
	)
	(footprint ""
		(layer "F.Cu")
		(at 71.871332 -282.664154 -90)
		(property "Reference" "C43"
			(at 0.298704 -4.020312 90)
			(unlocked yes)
			(layer "F.SilkS")
			(effects
				(font
					(size 0.7874 0.5842)
					(thickness 0.1524)
				)
			)
		)
		(property "Value" ""
			(at 0 0 270)
			(layer "F.Fab")
			(effects
				(font
					(size 1.27 1.27)
				)
			)
		)
		(duplicate_pad_numbers_are_jumpers no)
		(fp_line
			(start -1.2954 0.5842)
			(end -1.2954 -0.5842)
			(stroke
				(width 0.1524)
				(type default)
			)
			(layer "F.SilkS")
		)
		(fp_line
			(start 1.2954 0.5842)
			(end -1.2954 0.5842)
			(stroke
				(width 0.1524)
				(type default)
			)
			(layer "F.SilkS")
		)
		(fp_line
			(start -1.2954 -0.5842)
			(end 1.2954 -0.5842)
			(stroke
				(width 0.1524)
				(type default)
			)
			(layer "F.SilkS")
		)
		(fp_line
			(start 0 -0.5842)
			(end 0 0.5842)
			(stroke
				(width 0.1524)
				(type default)
			)
			(layer "F.SilkS")
		)
		(fp_line
			(start 1.2954 -0.5842)
			(end 1.2954 0.5842)
			(stroke
				(width 0.1524)
				(type default)
			)
			(layer "F.SilkS")
		)
		(fp_poly
			(pts
				(xy 0.8636 -0.4572) (xy 0.8636 -0.3556) (xy 1.143 -0.3556) (xy 1.143 0.3556) (xy 0.8636 0.3556)
				(xy 0.8636 0.4572) (xy -0.8636 0.4572) (xy -0.8636 0.3556) (xy -1.143 0.3556) (xy -1.143 -0.3556)
				(xy -0.8636 -0.3556) (xy -0.8636 -0.4572)
			)
			(stroke
				(width 0)
				(type default)
			)
			(fill no)
			(layer "F.CrtYd")
		)
		(fp_line
			(start -0.884936 0.504952)
			(end -0.884936 -0.504952)
			(stroke
				(width 0.1)
				(type default)
			)
			(layer "F.Fab")
		)
		(fp_line
			(start 0.884936 0.504952)
			(end -0.884936 0.504952)
			(stroke
				(width 0.1)
				(type default)
			)
			(layer "F.Fab")
		)
		(fp_line
			(start -0.884936 -0.504952)
			(end 0.884936 -0.504952)
			(stroke
				(width 0.1)
				(type default)
			)
			(layer "F.Fab")
		)
		(fp_line
			(start 0.884936 -0.504952)
			(end 0.884936 0.504952)
			(stroke
				(width 0.1)
				(type default)
			)
			(layer "F.Fab")
		)
		(pad "1" smd rect
			(at 0.7366 0)
			(size 0.7112 0.8128)
			(layers "F.Cu" "F.Mask" "F.Paste")
			(net "P12V")
		)
		(pad "2" smd rect
			(at -0.7366 0)
			(size 0.7112 0.8128)
			(layers "F.Cu" "F.Mask" "F.Paste")
			(net "GND")
		)
	)
)
